(kicad_pcb
	(version 20260206)
	(generator "pcbnew")
	(generator_version "10.0")
	(general
		(thickness 1.6)
		(legacy_teardrops no)
	)
	(paper "A4")
	(title_block
		(title "peb — Lightning_PEB_BRD.brd")
		(comment 1 "Lightning (Wiwynn / Facebook NVMe JBOF) / footprints 709-715 of 2563")
	)
	(layers
		(0 "F.Cu" signal "TOP")
		(4 "In1.Cu" signal "L2GND")
		(6 "In2.Cu" signal "L3")
		(8 "In3.Cu" signal "L4VCC")
		(10 "In4.Cu" signal "L5VCC")
		(12 "In5.Cu" signal "L6")
		(14 "In6.Cu" signal "L7GND")
		(2 "B.Cu" signal "BOTTOM")
		(9 "F.Adhes" user "F.Adhesive")
		(11 "B.Adhes" user "B.Adhesive")
		(13 "F.Paste" user "Package Geometry/Pastemask Top")
		(15 "B.Paste" user "Package Geometry/Pastemask Bottom")
		(5 "F.SilkS" user "Ref Des/Silkscreen Top")
		(7 "B.SilkS" user "Ref Des/Silkscreen Bottom")
		(1 "F.Mask" user "Board Geometry/Soldermask Top")
		(3 "B.Mask" user "Board Geometry/Soldermask Bottom")
		(17 "Dwgs.User" user "User.Drawings")
		(19 "Cmts.User" user "User.Comments")
		(21 "Eco1.User" user "User.Eco1")
		(23 "Eco2.User" user "User.Eco2")
		(25 "Edge.Cuts" user "Board Geometry/Outline")
		(27 "Margin" user)
		(31 "F.CrtYd" user "Package Geometry/Place Bound Top")
		(29 "B.CrtYd" user "Package Geometry/Place Bound Bottom")
		(35 "F.Fab" user "Ref Des/Assembly Top")
		(33 "B.Fab" user "Ref Des/Assembly Bottom")
	)
	(footprint ""
		(layer "F.Cu")
		(at 183.555386 -7.267702 -90)
		(property "Reference" "R2955"
			(at 0 0 270)
			(layer "F.SilkS")
			(hide yes)
			(effects
				(font
					(size 1.27 1.27)
				)
			)
		)
		(property "Value" "0R2J-2-GP"
			(at 0.064008 -3.993896 270)
			(unlocked yes)
			(layer "F.Fab")
			(hide yes)
			(effects
				(font
					(size 1.016 1.016)
					(thickness 0.1524)
				)
			)
		)
		(property "Device Type" "R402H16"
			(at 0.064008 -5.517896 270)
			(unlocked yes)
			(layer "F.Fab")
			(hide yes)
			(effects
				(font
					(size 1.016 1.016)
					(thickness 0.1524)
				)
			)
		)
		(duplicate_pad_numbers_are_jumpers no)
		(fp_line
			(start -0.508 -0.9398)
			(end -0.508 0.9398)
			(stroke
				(width 0.1524)
				(type default)
			)
			(layer "F.SilkS")
		)
		(fp_line
			(start 0.508 -0.9398)
			(end -0.508 -0.9398)
			(stroke
				(width 0.1524)
				(type default)
			)
			(layer "F.SilkS")
		)
		(fp_rect
			(start -0.508 0.9398)
			(end 0.508 -0.9398)
			(stroke
				(width 0)
				(type default)
			)
			(fill no)
			(layer "F.CrtYd")
		)
		(fp_rect
			(start -0.508 0.9398)
			(end 0.508 -0.9398)
			(stroke
				(width 0)
				(type default)
			)
			(fill no)
			(layer "F.Fab")
		)
		(pad "1" smd custom
			(at 0 -0.4445 270)
			(size 0.1397 0.1397)
			(layers "F.Cu" "F.Mask" "F.Paste")
			(net "HOST4_RST_N")
			(options
				(clearance outline)
				(anchor circle)
			)
			(primitives
				(gr_poly
					(pts
						(arc
							(start -0.1778 -0.2794)
							(mid -0.249642 -0.249642)
							(end -0.2794 -0.1778)
						)
						(arc
							(start -0.2794 0.1778)
							(mid -0.249642 0.249642)
							(end -0.1778 0.2794)
						)
						(arc
							(start 0.1778 0.2794)
							(mid 0.249642 0.249642)
							(end 0.2794 0.1778)
						)
						(arc
							(start 0.2794 -0.1778)
							(mid 0.249642 -0.249642)
							(end 0.1778 -0.2794)
						)
					)
					(width 0)
					(fill yes)
				)
			)
		)
		(pad "2" smd custom
			(at 0 0.4445 270)
			(size 0.1397 0.1397)
			(layers "F.Cu" "F.Mask" "F.Paste")
			(net "HOST4_RST_N_C")
			(options
				(clearance outline)
				(anchor circle)
			)
			(primitives
				(gr_poly
					(pts
						(arc
							(start -0.1778 -0.2794)
							(mid -0.249642 -0.249642)
							(end -0.2794 -0.1778)
						)
						(arc
							(start -0.2794 0.1778)
							(mid -0.249642 0.249642)
							(end -0.1778 0.2794)
						)
						(arc
							(start 0.1778 0.2794)
							(mid 0.249642 0.249642)
							(end 0.2794 0.1778)
						)
						(arc
							(start 0.2794 -0.1778)
							(mid 0.249642 -0.249642)
							(end 0.1778 -0.2794)
						)
					)
					(width 0)
					(fill yes)
				)
			)
		)
	)
	(footprint ""
		(layer "F.Cu")
		(at 122.0978 -101.4222)
		(property "Reference" "R862"
			(at 0 0 0)
			(layer "F.SilkS")
			(hide yes)
			(effects
				(font
					(size 1.27 1.27)
				)
			)
		)
		(property "Value" "0R2J-2-GP"
			(at 0.064008 -3.993896 0)
			(unlocked yes)
			(layer "F.Fab")
			(hide yes)
			(effects
				(font
					(size 1.016 1.016)
					(thickness 0.1524)
				)
			)
		)
		(property "Device Type" "R402H16"
			(at 0.064008 -5.517896 0)
			(unlocked yes)
			(layer "F.Fab")
			(hide yes)
			(effects
				(font
					(size 1.016 1.016)
					(thickness 0.1524)
				)
			)
		)
		(duplicate_pad_numbers_are_jumpers no)
		(fp_line
			(start -0.508 -0.9398)
			(end -0.508 0.9398)
			(stroke
				(width 0.1524)
				(type default)
			)
			(layer "F.SilkS")
		)
		(fp_line
			(start 0.508 -0.9398)
			(end -0.508 -0.9398)
			(stroke
				(width 0.1524)
				(type default)
			)
			(layer "F.SilkS")
		)
		(fp_rect
			(start -0.508 0.9398)
			(end 0.508 -0.9398)
			(stroke
				(width 0)
				(type default)
			)
			(fill no)
			(layer "F.CrtYd")
		)
		(fp_rect
			(start -0.508 0.9398)
			(end 0.508 -0.9398)
			(stroke
				(width 0)
				(type default)
			)
			(fill no)
			(layer "F.Fab")
		)
		(pad "1" smd custom
			(at 0 -0.4445)
			(size 0.1397 0.1397)
			(layers "F.Cu" "F.Mask" "F.Paste")
			(net "TWI_SCL0")
			(options
				(clearance outline)
				(anchor circle)
			)
			(primitives
				(gr_poly
					(pts
						(arc
							(start -0.1778 -0.2794)
							(mid -0.249642 -0.249642)
							(end -0.2794 -0.1778)
						)
						(arc
							(start -0.2794 0.1778)
							(mid -0.249642 0.249642)
							(end -0.1778 0.2794)
						)
						(arc
							(start 0.1778 0.2794)
							(mid 0.249642 0.249642)
							(end 0.2794 0.1778)
						)
						(arc
							(start 0.2794 -0.1778)
							(mid 0.249642 -0.249642)
							(end 0.1778 -0.2794)
						)
					)
					(width 0)
					(fill yes)
				)
			)
		)
		(pad "2" smd custom
			(at 0 0.4445)
			(size 0.1397 0.1397)
			(layers "F.Cu" "F.Mask" "F.Paste")
			(net "BUF_I2C_SCL_2_R")
			(options
				(clearance outline)
				(anchor circle)
			)
			(primitives
				(gr_poly
					(pts
						(arc
							(start -0.1778 -0.2794)
							(mid -0.249642 -0.249642)
							(end -0.2794 -0.1778)
						)
						(arc
							(start -0.2794 0.1778)
							(mid -0.249642 0.249642)
							(end -0.1778 0.2794)
						)
						(arc
							(start 0.1778 0.2794)
							(mid 0.249642 0.249642)
							(end 0.2794 0.1778)
						)
						(arc
							(start 0.2794 -0.1778)
							(mid 0.249642 -0.249642)
							(end 0.1778 -0.2794)
						)
					)
					(width 0)
					(fill yes)
				)
			)
		)
	)
	(footprint ""
		(layer "F.Cu")
		(at 35.2806 -184.8612 90)
		(property "Reference" "R964"
			(at 0 0 90)
			(layer "F.SilkS")
			(hide yes)
			(effects
				(font
					(size 1.27 1.27)
				)
			)
		)
		(property "Value" "0R2J-2-GP"
			(at 0.064008 -3.993896 90)
			(unlocked yes)
			(layer "F.Fab")
			(hide yes)
			(effects
				(font
					(size 1.016 1.016)
					(thickness 0.1524)
				)
			)
		)
		(property "Device Type" "R402H16"
			(at 0.064008 -5.517896 90)
			(unlocked yes)
			(layer "F.Fab")
			(hide yes)
			(effects
				(font
					(size 1.016 1.016)
					(thickness 0.1524)
				)
			)
		)
		(duplicate_pad_numbers_are_jumpers no)
		(fp_line
			(start 0.508 -0.9398)
			(end -0.508 -0.9398)
			(stroke
				(width 0.1524)
				(type default)
			)
			(layer "F.SilkS")
		)
		(fp_line
			(start -0.508 -0.9398)
			(end -0.508 0.9398)
			(stroke
				(width 0.1524)
				(type default)
			)
			(layer "F.SilkS")
		)
		(fp_rect
			(start -0.508 0.9398)
			(end 0.508 -0.9398)
			(stroke
				(width 0)
				(type default)
			)
			(fill no)
			(layer "F.CrtYd")
		)
		(fp_rect
			(start -0.508 0.9398)
			(end 0.508 -0.9398)
			(stroke
				(width 0)
				(type default)
			)
			(fill no)
			(layer "F.Fab")
		)
		(pad "1" smd custom
			(at 0 -0.4445 90)
			(size 0.1397 0.1397)
			(layers "F.Cu" "F.Mask" "F.Paste")
			(net "BUF_I2C5_SDA_R")
			(options
				(clearance outline)
				(anchor circle)
			)
			(primitives
				(gr_poly
					(pts
						(arc
							(start -0.1778 -0.2794)
							(mid -0.249642 -0.249642)
							(end -0.2794 -0.1778)
						)
						(arc
							(start -0.2794 0.1778)
							(mid -0.249642 0.249642)
							(end -0.1778 0.2794)
						)
						(arc
							(start 0.1778 0.2794)
							(mid 0.249642 0.249642)
							(end 0.2794 0.1778)
						)
						(arc
							(start 0.2794 -0.1778)
							(mid 0.249642 -0.249642)
							(end 0.1778 -0.2794)
						)
					)
					(width 0)
					(fill yes)
				)
			)
		)
		(pad "2" smd custom
			(at 0 0.4445 90)
			(size 0.1397 0.1397)
			(layers "F.Cu" "F.Mask" "F.Paste")
			(net "BMC_I2C5_D_PEB_DEVICE_SDA")
			(options
				(clearance outline)
				(anchor circle)
			)
			(primitives
				(gr_poly
					(pts
						(arc
							(start -0.1778 -0.2794)
							(mid -0.249642 -0.249642)
							(end -0.2794 -0.1778)
						)
						(arc
							(start -0.2794 0.1778)
							(mid -0.249642 0.249642)
							(end -0.1778 0.2794)
						)
						(arc
							(start 0.1778 0.2794)
							(mid 0.249642 0.249642)
							(end 0.2794 0.1778)
						)
						(arc
							(start 0.2794 -0.1778)
							(mid 0.249642 -0.249642)
							(end 0.1778 -0.2794)
						)
					)
					(width 0)
					(fill yes)
				)
			)
		)
	)
	(footprint ""
		(layer "F.Cu")
		(at 13.812012 -60.300108 90)
		(property "Reference" "PAD5"
			(at 0 0 90)
			(layer "F.SilkS")
			(hide yes)
			(effects
				(font
					(size 1.27 1.27)
				)
			)
		)
		(property "Value" "STF256R168H278-GP"
			(at -4.826 0.0508 90)
			(unlocked yes)
			(layer "F.Fab")
			(hide yes)
			(effects
				(font
					(size 1.016 1.016)
					(thickness 0.1524)
				)
			)
		)
		(property "Device Type" "STF256R168H278"
			(at -4.826 -1.4732 90)
			(unlocked yes)
			(layer "F.Fab")
			(hide yes)
			(effects
				(font
					(size 1.016 1.016)
					(thickness 0.1524)
				)
			)
		)
		(duplicate_pad_numbers_are_jumpers no)
		(fp_circle
			(center 0 0)
			(end 0 3.6068)
			(stroke
				(width 0.3048)
				(type default)
			)
			(fill no)
			(layer "F.SilkS")
		)
		(fp_poly
			(pts
				(arc
					(start 0 3.7592)
					(mid 0 -3.7592)
					(end 0 3.7592)
				)
			)
			(stroke
				(width 0)
				(type default)
			)
			(fill no)
			(layer "B.CrtYd")
		)
		(fp_poly
			(pts
				(arc
					(start 0 2.5019)
					(mid 0 -2.5019)
					(end 0 2.5019)
				)
			)
			(stroke
				(width 0)
				(type default)
			)
			(fill no)
			(layer "F.CrtYd")
		)
		(fp_poly
			(pts
				(arc
					(start 3.7592 0.00635)
					(mid -3.759205 0)
					(end 3.7592 -0.00635)
				)
				(arc
					(start 2.5019 -0.00635)
					(mid -2.501908 0)
					(end 2.5019 0.00635)
				)
			)
			(stroke
				(width 0)
				(type default)
			)
			(fill no)
			(layer "F.CrtYd")
		)
		(fp_poly
			(pts
				(arc
					(start 0 3.7592)
					(mid 0 -3.7592)
					(end 0 3.7592)
				)
			)
			(stroke
				(width 0)
				(type default)
			)
			(fill no)
			(layer "B.Fab")
		)
		(fp_poly
			(pts
				(arc
					(start 0 3.7592)
					(mid 0 -3.7592)
					(end 0 3.7592)
				)
			)
			(stroke
				(width 0)
				(type default)
			)
			(fill no)
			(layer "F.Fab")
		)
		(pad "1" thru_hole circle
			(at 0 0 90)
			(size 6.5024 6.5024)
			(drill 4.2672)
			(layers "*.Cu" "*.Mask")
			(remove_unused_layers no)
			(net "GND")
			(clearance -0.6096)
			(thermal_gap 0.3048)
			(padstack
				(mode front_inner_back)
				(layer "Inner"
					(shape circle)
					(size 4.6736 4.6736)
					(clearance 0.3048)
				)
				(layer "B.Cu"
					(shape circle)
					(size 6.5024 6.5024)
					(clearance -0.6096)
				)
			)
		)
	)
	(footprint ""
		(layer "F.Cu")
		(at 9.99998 -203.499974)
		(property "Reference" ""
			(at 0 0 0)
			(layer "F.SilkS")
			(hide yes)
			(effects
				(font
					(size 1.27 1.27)
				)
			)
		)
		(property "Value" "*"
			(at -0.1524 -7.3914 0)
			(unlocked yes)
			(layer "F.Fab")
			(hide yes)
			(effects
				(font
					(size 1.016 1.016)
					(thickness 0.1524)
				)
			)
		)
		(duplicate_pad_numbers_are_jumpers no)
		(fp_poly
			(pts
				(arc
					(start 4.3053 0)
					(mid -4.3053 0)
					(end 4.3053 0)
				)
			)
			(stroke
				(width 0)
				(type default)
			)
			(fill no)
			(layer "B.CrtYd")
		)
		(fp_poly
			(pts
				(arc
					(start 4.3053 0)
					(mid -4.3053 0)
					(end 4.3053 0)
				)
			)
			(stroke
				(width 0)
				(type default)
			)
			(fill no)
			(layer "F.CrtYd")
		)
		(fp_poly
			(pts
				(arc
					(start 4.3053 0)
					(mid -4.3053 0)
					(end 4.3053 0)
				)
			)
			(stroke
				(width 0)
				(type default)
			)
			(fill no)
			(layer "B.Fab")
		)
		(fp_poly
			(pts
				(arc
					(start 4.3053 0)
					(mid -4.3053 0)
					(end 4.3053 0)
				)
			)
			(stroke
				(width 0)
				(type default)
			)
			(fill no)
			(layer "F.Fab")
		)
		(pad "1" thru_hole circle
			(at 0 0)
			(size 8.001 8.001)
			(drill 3.81)
			(layers "*.Cu" "*.Mask")
			(remove_unused_layers no)
			(net "Net_114")
			(clearance -1.5875)
			(thermal_gap 0.3048)
			(padstack
				(mode front_inner_back)
				(layer "Inner"
					(shape circle)
					(size 4.2164 4.2164)
					(clearance 0.3048)
				)
				(layer "B.Cu"
					(shape circle)
					(size 8.001 8.001)
					(clearance -1.5875)
				)
			)
		)
	)
	(footprint ""
		(layer "F.Cu")
		(at 324.739 -86.487)
		(property "Reference" "R4159"
			(at 0 0 0)
			(layer "F.SilkS")
			(hide yes)
			(effects
				(font
					(size 1.27 1.27)
				)
			)
		)
		(property "Value" "4K7R2F-GP"
			(at 0.064008 -3.993896 0)
			(unlocked yes)
			(layer "F.Fab")
			(hide yes)
			(effects
				(font
					(size 1.016 1.016)
					(thickness 0.1524)
				)
			)
		)
		(property "Device Type" "R402H16"
			(at 0.064008 -5.517896 0)
			(unlocked yes)
			(layer "F.Fab")
			(hide yes)
			(effects
				(font
					(size 1.016 1.016)
					(thickness 0.1524)
				)
			)
		)
		(duplicate_pad_numbers_are_jumpers no)
		(fp_line
			(start -0.508 -0.9398)
			(end -0.508 0.9398)
			(stroke
				(width 0.1524)
				(type default)
			)
			(layer "F.SilkS")
		)
		(fp_line
			(start 0.508 -0.9398)
			(end -0.508 -0.9398)
			(stroke
				(width 0.1524)
				(type default)
			)
			(layer "F.SilkS")
		)
		(fp_rect
			(start -0.508 0.9398)
			(end 0.508 -0.9398)
			(stroke
				(width 0)
				(type default)
			)
			(fill no)
			(layer "F.CrtYd")
		)
		(fp_rect
			(start -0.508 0.9398)
			(end 0.508 -0.9398)
			(stroke
				(width 0)
				(type default)
			)
			(fill no)
			(layer "F.Fab")
		)
		(pad "1" smd custom
			(at 0 -0.4445)
			(size 0.1397 0.1397)
			(layers "F.Cu" "F.Mask" "F.Paste")
			(net "UPLINK2")
			(options
				(clearance outline)
				(anchor circle)
			)
			(primitives
				(gr_poly
					(pts
						(arc
							(start -0.1778 -0.2794)
							(mid -0.249642 -0.249642)
							(end -0.2794 -0.1778)
						)
						(arc
							(start -0.2794 0.1778)
							(mid -0.249642 0.249642)
							(end -0.1778 0.2794)
						)
						(arc
							(start 0.1778 0.2794)
							(mid 0.249642 0.249642)
							(end 0.2794 0.1778)
						)
						(arc
							(start 0.2794 -0.1778)
							(mid 0.249642 -0.249642)
							(end 0.1778 -0.2794)
						)
					)
					(width 0)
					(fill yes)
				)
			)
		)
		(pad "2" smd custom
			(at 0 0.4445)
			(size 0.1397 0.1397)
			(layers "F.Cu" "F.Mask" "F.Paste")
			(net "P3V3_STBY")
			(options
				(clearance outline)
				(anchor circle)
			)
			(primitives
				(gr_poly
					(pts
						(arc
							(start -0.1778 -0.2794)
							(mid -0.249642 -0.249642)
							(end -0.2794 -0.1778)
						)
						(arc
							(start -0.2794 0.1778)
							(mid -0.249642 0.249642)
							(end -0.1778 0.2794)
						)
						(arc
							(start 0.1778 0.2794)
							(mid 0.249642 0.249642)
							(end 0.2794 0.1778)
						)
						(arc
							(start 0.2794 -0.1778)
							(mid 0.249642 -0.249642)
							(end 0.1778 -0.2794)
						)
					)
					(width 0)
					(fill yes)
				)
			)
		)
	)
	(footprint ""
		(layer "F.Cu")
		(at 10.5791 -53.594 180)
		(property "Reference" "R595"
			(at 0 0 180)
			(layer "F.SilkS")
			(hide yes)
			(effects
				(font
					(size 1.27 1.27)
				)
			)
		)
		(property "Value" "0R2J-2-GP"
			(at 0.064008 -3.993896 180)
			(unlocked yes)
			(layer "F.Fab")
			(hide yes)
			(effects
				(font
					(size 1.016 1.016)
					(thickness 0.1524)
				)
			)
		)
		(property "Device Type" "R402H16"
			(at 0.064008 -5.517896 180)
			(unlocked yes)
			(layer "F.Fab")
			(hide yes)
			(effects
				(font
					(size 1.016 1.016)
					(thickness 0.1524)
				)
			)
		)
		(duplicate_pad_numbers_are_jumpers no)
		(fp_line
			(start 0.508 -0.9398)
			(end -0.508 -0.9398)
			(stroke
				(width 0.1524)
				(type default)
			)
			(layer "F.SilkS")
		)
		(fp_line
			(start -0.508 -0.9398)
			(end -0.508 0.9398)
			(stroke
				(width 0.1524)
				(type default)
			)
			(layer "F.SilkS")
		)
		(fp_rect
			(start -0.508 0.9398)
			(end 0.508 -0.9398)
			(stroke
				(width 0)
				(type default)
			)
			(fill no)
			(layer "F.CrtYd")
		)
		(fp_rect
			(start -0.508 0.9398)
			(end 0.508 -0.9398)
			(stroke
				(width 0)
				(type default)
			)
			(fill no)
			(layer "F.Fab")
		)
		(pad "1" smd custom
			(at 0 -0.4445 180)
			(size 0.1397 0.1397)
			(layers "F.Cu" "F.Mask" "F.Paste")
			(net "NIC0_MDI0_N0_R")
			(options
				(clearance outline)
				(anchor circle)
			)
			(primitives
				(gr_poly
					(pts
						(arc
							(start -0.1778 -0.2794)
							(mid -0.249642 -0.249642)
							(end -0.2794 -0.1778)
						)
						(arc
							(start -0.2794 0.1778)
							(mid -0.249642 0.249642)
							(end -0.1778 0.2794)
						)
						(arc
							(start 0.1778 0.2794)
							(mid 0.249642 0.249642)
							(end 0.2794 0.1778)
						)
						(arc
							(start 0.2794 -0.1778)
							(mid 0.249642 -0.249642)
							(end 0.1778 -0.2794)
						)
					)
					(width 0)
					(fill yes)
				)
			)
		)
		(pad "2" smd custom
			(at 0 0.4445 180)
			(size 0.1397 0.1397)
			(layers "F.Cu" "F.Mask" "F.Paste")
			(net "NIC0_MDI0_N0")
			(options
				(clearance outline)
				(anchor circle)
			)
			(primitives
				(gr_poly
					(pts
						(arc
							(start -0.1778 -0.2794)
							(mid -0.249642 -0.249642)
							(end -0.2794 -0.1778)
						)
						(arc
							(start -0.2794 0.1778)
							(mid -0.249642 0.249642)
							(end -0.1778 0.2794)
						)
						(arc
							(start 0.1778 0.2794)
							(mid 0.249642 0.249642)
							(end 0.2794 0.1778)
						)
						(arc
							(start 0.2794 -0.1778)
							(mid 0.249642 -0.249642)
							(end 0.1778 -0.2794)
						)
					)
					(width 0)
					(fill yes)
				)
			)
		)
	)
)
